# BASEBOARD_FAB2 (Tioga Pass) — schematic netlist excerpt (pin names and nets, part order shuffled) for the footprints in the layout excerpt that follows; sources: Cadence DE-HDL packaged netlist, KiCad conversion of Wiwynn_Tioga_Pass_MB.brd

C4E19  CAP  1.0UF 16V 10% X6S  pkg 0402  page 202 : A = VR_FET_SW_P12V_STBY_PVCCIN_CPU0 ; B = GND
C2G13  CAP_A  47UF 4V 20% X5R  pkg 0603V  page 225 : A = PVDDQ_GHJ ; B = GND

(kicad_pcb
	(version 20260206)
	(generator "pcbnew")
	(generator_version "10.0")
	(general
		(thickness 1.6)
		(legacy_teardrops no)
	)
	(paper "A4")
	(title_block
		(title "Wiwynn_Tioga_Pass_MB.brd")
		(comment 1 "Tioga Pass / footprints 2179-2180 of 4770")
	)
	(layers
		(0 "F.Cu" signal "TOP")
		(4 "In1.Cu" signal "L2GND")
		(6 "In2.Cu" signal "L3")
		(8 "In3.Cu" signal "L4GND")
		(10 "In4.Cu" signal "L5")
		(12 "In5.Cu" signal "L6GND")
		(14 "In6.Cu" signal "L7VCC")
		(16 "In7.Cu" signal "L8VCC")
		(18 "In8.Cu" signal "L9GND")
		(20 "In9.Cu" signal "L10")
		(22 "In10.Cu" signal "L11GND")
		(24 "In11.Cu" signal "L12")
		(26 "In12.Cu" signal "L13GND")
		(2 "B.Cu" signal "BOTTOM")
		(9 "F.Adhes" user "F.Adhesive")
		(11 "B.Adhes" user "B.Adhesive")
		(13 "F.Paste" user "Package Geometry/Pastemask Top")
		(15 "B.Paste" user "Package Geometry/Pastemask Bottom")
		(5 "F.SilkS" user "Ref Des/Silkscreen Top")
		(7 "B.SilkS" user "Ref Des/Silkscreen Bottom")
		(1 "F.Mask" user "Board Geometry/Soldermask Top")
		(3 "B.Mask" user "Board Geometry/Soldermask Bottom")
		(17 "Dwgs.User" user "User.Drawings")
		(19 "Cmts.User" user "User.Comments")
		(21 "Eco1.User" user "User.Eco1")
		(23 "Eco2.User" user "User.Eco2")
		(25 "Edge.Cuts" user "Board Geometry/Outline")
		(27 "Margin" user)
		(31 "F.CrtYd" user "Package Geometry/Place Bound Top")
		(29 "B.CrtYd" user "Package Geometry/Place Bound Bottom")
		(35 "F.Fab" user "Ref Des/Assembly Top")
		(33 "B.Fab" user "Ref Des/Assembly Bottom")
	)
	(footprint ""
		(layer "F.Cu")
		(at 101.3968 -3.3528 90)
		(property "Reference" "C2G13"
			(at 1.848866 0.752348 90)
			(unlocked yes)
			(layer "F.SilkS")
			(effects
				(font
					(size 1.27 0.9652)
					(thickness 0.1524)
				)
			)
		)
		(property "Value" ""
			(at 0 0 90)
			(layer "F.Fab")
			(effects
				(font
					(size 1.27 1.27)
				)
			)
		)
		(duplicate_pad_numbers_are_jumpers no)
		(fp_rect
			(start -0.500126 1.598422)
			(end 0.500126 -0.201422)
			(stroke
				(width 0)
				(type default)
			)
			(fill no)
			(layer "F.CrtYd")
		)
		(fp_line
			(start 0.500126 -0.201422)
			(end 0.500126 1.598422)
			(stroke
				(width 0.1)
				(type default)
			)
			(layer "F.Fab")
		)
		(fp_line
			(start -0.500126 -0.201422)
			(end 0.500126 -0.201422)
			(stroke
				(width 0.1)
				(type default)
			)
			(layer "F.Fab")
		)
		(fp_line
			(start 0.500126 1.598422)
			(end -0.500126 1.598422)
			(stroke
				(width 0.1)
				(type default)
			)
			(layer "F.Fab")
		)
		(fp_line
			(start -0.500126 1.598422)
			(end -0.500126 -0.201422)
			(stroke
				(width 0.1)
				(type default)
			)
			(layer "F.Fab")
		)
		(pad "1" smd rect
			(at 0 0)
			(size 0.889 0.9906)
			(layers "F.Cu" "F.Mask" "F.Paste")
			(net "PVDDQ_GHJ")
		)
		(pad "2" smd rect
			(at 0 1.397)
			(size 0.889 0.9906)
			(layers "F.Cu" "F.Mask" "F.Paste")
			(net "GND")
		)
		(zone
			(layer "F.Cu")
			(hatch none 0.5)
			(connect_pads
				(clearance 0)
			)
			(min_thickness 0.25)
			(keepout
				(tracks allowed)
				(vias not_allowed)
				(pads allowed)
				(copperpour not_allowed)
				(footprints allowed)
			)
			(placement
				(enabled no)
				(sheetname "")
			)
			(fill
				(thermal_gap 0.5)
				(thermal_bridge_width 0.5)
				(island_removal_mode 0)
			)
			(polygon
				(pts
					(xy 102.3493 -2.8575) (xy 102.3493 -3.8481) (xy 101.8413 -3.8481) (xy 101.8413 -2.8575)
				)
			)
		)
		(zone
			(layer "F.Cu")
			(hatch none 0.5)
			(connect_pads
				(clearance 0)
			)
			(min_thickness 0.25)
			(keepout
				(tracks not_allowed)
				(vias allowed)
				(pads allowed)
				(copperpour not_allowed)
				(footprints allowed)
			)
			(placement
				(enabled no)
				(sheetname "")
			)
			(fill
				(thermal_gap 0.5)
				(thermal_bridge_width 0.5)
				(island_removal_mode 0)
			)
			(polygon
				(pts
					(xy 102.3493 -2.8575) (xy 102.3493 -3.8481) (xy 101.8413 -3.8481) (xy 101.8413 -2.8575)
				)
			)
		)
	)
	(footprint ""
		(layer "F.Cu")
		(at 194.7545 -59.817 -90)
		(property "Reference" "C4E19"
			(at 0 0 270)
			(layer "F.SilkS")
			(hide yes)
			(effects
				(font
					(size 1.27 1.27)
				)
			)
		)
		(property "Value" ""
			(at 0 0 270)
			(layer "F.Fab")
			(effects
				(font
					(size 1.27 1.27)
				)
			)
		)
		(duplicate_pad_numbers_are_jumpers no)
		(fp_poly
			(pts
				(xy 0.3048 -0.1016) (xy 0.3048 0.9906) (xy -0.3048 0.9906) (xy -0.3048 -0.1016)
			)
			(stroke
				(width 0)
				(type default)
			)
			(fill no)
			(layer "F.CrtYd")
		)
		(fp_line
			(start -0.3048 0.9906)
			(end 0.3048 0.9906)
			(stroke
				(width 0.1)
				(type default)
			)
			(layer "F.Fab")
		)
		(fp_line
			(start 0.3048 0.9906)
			(end 0.3048 -0.1016)
			(stroke
				(width 0.1)
				(type default)
			)
			(layer "F.Fab")
		)
		(fp_line
			(start -0.3048 -0.1016)
			(end -0.3048 0.9906)
			(stroke
				(width 0.1)
				(type default)
			)
			(layer "F.Fab")
		)
		(fp_line
			(start 0.3048 -0.1016)
			(end -0.3048 -0.1016)
			(stroke
				(width 0.1)
				(type default)
			)
			(layer "F.Fab")
		)
		(pad "1" smd rect
			(at 0 0 270)
			(size 0.508 0.508)
			(layers "F.Cu" "F.Mask" "F.Paste")
			(net "VR_FET_SW_P12V_STBY_PVCCIN_CPU0")
		)
		(pad "2" smd rect
			(at 0 0.889 270)
			(size 0.508 0.508)
			(layers "F.Cu" "F.Mask" "F.Paste")
			(net "GND")
		)
		(zone
			(layer "F.Cu")
			(hatch none 0.5)
			(connect_pads
				(clearance 0)
			)
			(min_thickness 0.25)
			(keepout
				(tracks not_allowed)
				(vias allowed)
				(pads allowed)
				(copperpour not_allowed)
				(footprints allowed)
			)
			(placement
				(enabled no)
				(sheetname "")
			)
			(fill
				(thermal_gap 0.5)
				(thermal_bridge_width 0.5)
				(island_removal_mode 0)
			)
			(polygon
				(pts
					(xy 194.1195 -60.071) (xy 194.1195 -59.563) (xy 194.5005 -59.563) (xy 194.5005 -60.071)
				)
			)
		)
		(zone
			(layer "F.Cu")
			(hatch none 0.5)
			(connect_pads
				(clearance 0)
			)
			(min_thickness 0.25)
			(keepout
				(tracks allowed)
				(vias not_allowed)
				(pads allowed)
				(copperpour not_allowed)
				(footprints allowed)
			)
			(placement
				(enabled no)
				(sheetname "")
			)
			(fill
				(thermal_gap 0.5)
				(thermal_bridge_width 0.5)
				(island_removal_mode 0)
			)
			(polygon
				(pts
					(xy 194.5005 -60.071) (xy 194.5005 -59.563) (xy 194.1195 -59.563) (xy 194.1195 -60.071)
				)
			)
		)
	)
)
